#ISCELL
  mstr_misc dns *
  *
#ISCELL
  pure_quanta quanta_title_block_c *
  *
#ISCELL
  pure_quanta_power universal_gnd *
  page188_i1
#CELL
  pure_quanta q_res *
  page188_i11
#ISCELL
  pure_quanta_power universal_gnd *
  page188_i15
#CELL
  pure_quanta q_res *
  page188_i17
#CELL
  pure_quanta q_res *
  page188_i18
#CELL
  pure_quanta q_cap *
  page188_i19
#CELL
  pure_quanta q_cap *
  page188_i2
#CELL
  pure_quanta q_cap *
  page188_i20
#CELL
  pure_quanta q_cap *
  page188_i21
#CELL
  pure_quanta q_inductor4p_14 *
  page188_i23
#ISCELL
  pure_quanta_power universal_gnd *
  page188_i24
#CELL
  pure_quanta q_cap *
  page188_i25
#ISCELL
  pure_quanta_power vcc_core *
  page188_i26
#ISCELL
  standard offpage *
  page188_i27
#ISCELL
  standard offpage *
  page188_i3
#CELL
  pure_quanta q_cap *
  page188_i30
#ISCELL
  pure_quanta_power universal_gnd *
  page188_i31
#CELL
  pure_quanta q_cap *
  page188_i32
#ISCELL
  pure_quanta_power vcc_core *
  page188_i33
#ISCELL
  standard offpage *
  page188_i34
#CELL
  pure_quanta isl99390frztr5935 *
  page188_i35
#CELL
  pure_quanta q_cap *
  page188_i36
#CELL
  pure_quanta q_cap *
  page188_i37
#ISCELL
  pure_quanta_power universal_gnd *
  page188_i38
#ISCELL
  pure_quanta_power universal_gnd *
  page188_i39
#ISCELL
  standard offpage *
  page188_i4
#CELL
  pure_quanta q_res *
  page188_i40
#CELL
  pure_quanta q_cap *
  page188_i41
#ISCELL
  pure_quanta_power vcc_core *
  page188_i42
#CELL
  pure_quanta isl99390frztr5935 *
  page188_i43
#ISCELL
  pure_quanta_power vcc_core *
  page188_i44
#CELL
  pure_quanta q_cap *
  page188_i45
#ISCELL
  pure_quanta_power universal_gnd *
  page188_i46
#CELL
  pure_quanta q_cap *
  page188_i47
#ISCELL
  standard offpage *
  page188_i48
#ISCELL
  pure_quanta_power vcc_core *
  page188_i49
#ISCELL
  pure_quanta_power universal_gnd *
  page188_i5
#CELL
  pure_quanta q_cap *
  page188_i50
#ISCELL
  pure_quanta_power universal_gnd *
  page188_i51
#CELL
  pure_quanta q_inductor4p_14 *
  page188_i52
#CELL
  pure_quanta q_cap *
  page188_i53
#CELL
  pure_quanta q_cap *
  page188_i55
#CELL
  pure_quanta q_cap *
  page188_i56
#CELL
  pure_quanta q_cap *
  page188_i57
#CELL
  pure_quanta q_res *
  page188_i58
#CELL
  pure_quanta q_res *
  page188_i59
#ISCELL
  standard offpage *
  page188_i6
#CELL
  pure_quanta q_cap *
  page188_i60
#ISCELL
  pure_quanta_power vcc_core *
  page188_i61
#CELL
  pure_quanta q_cap *
  page188_i62
#ISCELL
  pure_quanta_power universal_gnd *
  page188_i63
#CELL
  pure_quanta q_res *
  page188_i64
#ISCELL
  standard offpage *
  page188_i65
#CELL
  pure_quanta q_cap *
  page188_i66
#ISCELL
  pure_quanta_power universal_gnd *
  page188_i67
#CELL
  pure_quanta q_res *
  page188_i68
#ISCELL
  standard offpage *
  page188_i69
#ISCELL
  pure_quanta_power universal_gnd *
  page188_i70
#CELL
  pure_quanta q_cap *
  page188_i71
#ISCELL
  pure_quanta_power universal_gnd *
  page188_i72
#ISCELL
  standard offpage *
  page188_i73
#ISCELL
  pure_quanta_power universal_gnd *
  page188_i74
#ISCELL
  standard offpage *
  page188_i75
#ISCELL
  standard offpage *
  page188_i8
#CELL
  pure_quanta q_cap *
  page188_i80
#ISCELL
  pure_quanta_power universal_gnd *
  page188_i81
#CELL
  pure_quanta q_res *
  page188_i82
#CELL
  pure_quanta q_cap *
  page188_i83
#ISCELL
  pure_quanta_power universal_gnd *
  page188_i84
#CELL
  pure_quanta q_res *
  page188_i85
#CELL
  pure_quanta q_cap *
  page188_i86
#CELL
  pure_quanta q_inductor *
  page188_i87
#ISCELL
  pure_quanta_power universal_gnd *
  page188_i88
